# S9S_MB_2U (Grand Teton) — schematic netlist excerpt (pin names and nets, part order shuffled) for the footprints in the layout excerpt that follows; sources: Cadence DE-HDL packaged netlist, KiCad conversion of 03242023_DA0F0TMBIJ0_F0T_Motherboard_J_brd_V01_OCP.brd

PC323  Q_CAPP  330UF 2.5V +10/-35% EMPTY  pkg SMLF  page 267 : A = PVCCIN_CPU0 ; B = GND
R68  Q_RES  33.2 1% CHIP  pkg 0402LF  page 43 : A = PWRGD_PLT_AUX_CPU1_LVT3_R ; B = PWRGD_PLT_AUX_CPU1_LVT3

(kicad_pcb
	(version 20260206)
	(generator "pcbnew")
	(generator_version "10.0")
	(general
		(thickness 1.6)
		(legacy_teardrops no)
	)
	(paper "A4")
	(title_block
		(title "03242023_DA0F0TMBIJ0_F0T_Motherboard_J_brd_V01_OCP.brd")
		(comment 1 "Grand Teton / footprints 5817-5818 of 6105")
	)
	(layers
		(0 "F.Cu" signal "TOP")
		(4 "In1.Cu" signal "GND")
		(6 "In2.Cu" signal "IN1")
		(8 "In3.Cu" signal "GND1")
		(10 "In4.Cu" signal "IN2")
		(12 "In5.Cu" signal "GND2")
		(14 "In6.Cu" signal "IN3")
		(16 "In7.Cu" signal "GND3")
		(18 "In8.Cu" signal "VCC")
		(20 "In9.Cu" signal "VCC1")
		(22 "In10.Cu" signal "GND4")
		(24 "In11.Cu" signal "IN4")
		(26 "In12.Cu" signal "GND5")
		(28 "In13.Cu" signal "IN5")
		(30 "In14.Cu" signal "GND6")
		(32 "In15.Cu" signal "IN6")
		(34 "In16.Cu" signal "GND7")
		(2 "B.Cu" signal "BOTTOM")
		(9 "F.Adhes" user "F.Adhesive")
		(11 "B.Adhes" user "B.Adhesive")
		(13 "F.Paste" user "Package Geometry/Pastemask Top")
		(15 "B.Paste" user "Package Geometry/Pastemask Bottom")
		(5 "F.SilkS" user "Ref Des/Silkscreen Top")
		(7 "B.SilkS" user "Ref Des/Silkscreen Bottom")
		(1 "F.Mask" user "Board Geometry/Soldermask Top")
		(3 "B.Mask" user "Board Geometry/Soldermask Bottom")
		(17 "Dwgs.User" user "User.Drawings")
		(19 "Cmts.User" user "User.Comments")
		(21 "Eco1.User" user "User.Eco1")
		(23 "Eco2.User" user "User.Eco2")
		(25 "Edge.Cuts" user "Board Geometry/Outline")
		(27 "Margin" user)
		(31 "F.CrtYd" user "Package Geometry/Place Bound Top")
		(29 "B.CrtYd" user "Package Geometry/Place Bound Bottom")
		(35 "F.Fab" user "Ref Des/Assembly Top")
		(33 "B.Fab" user "Ref Des/Assembly Bottom")
	)
	(footprint ""
		(layer "B.Cu")
		(at 377.485402 -329.921616 -90)
		(property "Reference" "PC323"
			(at 0 0 90)
			(layer "B.SilkS")
			(hide yes)
			(effects
				(font
					(size 1.27 1.27)
				)
				(justify mirror)
			)
		)
		(property "Value" ""
			(at 0 0 90)
			(layer "B.Fab")
			(effects
				(font
					(size 1.27 1.27)
				)
				(justify mirror)
			)
		)
		(duplicate_pad_numbers_are_jumpers no)
		(fp_line
			(start -4.533392 2.249932)
			(end 4.533392 2.249932)
			(stroke
				(width 0.1524)
				(type default)
			)
			(layer "B.SilkS")
		)
		(fp_line
			(start 4.533392 2.249932)
			(end 4.533392 -2.249932)
			(stroke
				(width 0.1524)
				(type default)
			)
			(layer "B.SilkS")
		)
		(fp_line
			(start -4.533392 -2.249932)
			(end -4.533392 2.249932)
			(stroke
				(width 0.1524)
				(type default)
			)
			(layer "B.SilkS")
		)
		(fp_line
			(start 4.533392 -2.249932)
			(end -4.533392 -2.249932)
			(stroke
				(width 0.1524)
				(type default)
			)
			(layer "B.SilkS")
		)
		(fp_rect
			(start 5.39242 2.326132)
			(end 4.533392 -2.326132)
			(stroke
				(width 0)
				(type default)
			)
			(fill yes)
			(layer "B.SilkS")
		)
		(fp_line
			(start -3.750056 2.249932)
			(end 3.750056 2.249932)
			(stroke
				(width 0.1)
				(type default)
			)
			(layer "B.Fab")
		)
		(fp_line
			(start 3.750056 2.249932)
			(end 3.750056 -2.249932)
			(stroke
				(width 0.1)
				(type default)
			)
			(layer "B.Fab")
		)
		(fp_line
			(start -3.750056 -2.249932)
			(end -3.750056 2.249932)
			(stroke
				(width 0.1)
				(type default)
			)
			(layer "B.Fab")
		)
		(fp_line
			(start 3.750056 -2.249932)
			(end -3.750056 -2.249932)
			(stroke
				(width 0.1)
				(type default)
			)
			(layer "B.Fab")
		)
		(fp_text user "-"
			(at -4.673092 1.617472 270)
			(unlocked yes)
			(layer "B.SilkS")
			(effects
				(font
					(size 1.905 1.4224)
					(thickness 0.1524)
				)
				(justify left mirror)
			)
		)
		(fp_text user "+"
			(at 6.322314 0.786384 180)
			(unlocked yes)
			(layer "B.SilkS")
			(effects
				(font
					(size 1.905 1.4224)
					(thickness 0.1524)
				)
				(justify left mirror)
			)
		)
		(fp_text user "+"
			(at 6.322314 0.786384 180)
			(unlocked yes)
			(layer "B.Fab")
			(effects
				(font
					(size 1.905 1.4224)
					(thickness 0.1524)
				)
				(justify left mirror)
			)
		)
		(fp_text user "-"
			(at -4.8514 -0.14605 270)
			(unlocked yes)
			(layer "B.Fab")
			(effects
				(font
					(size 1.905 1.4224)
					(thickness 0.1524)
				)
				(justify left mirror)
			)
		)
		(pad "1" smd rect
			(at 3.199892 0 90)
			(size 2.413 2.8194)
			(layers "B.Cu" "B.Mask" "B.Paste")
			(net "PVCCIN_CPU0")
		)
		(pad "2" smd rect
			(at -3.199892 0 90)
			(size 2.413 2.8194)
			(layers "B.Cu" "B.Mask" "B.Paste")
			(net "GND")
		)
	)
	(footprint ""
		(layer "B.Cu")
		(at 156.1465 -192.77711 -90)
		(property "Reference" "R68"
			(at 0 0 90)
			(layer "B.SilkS")
			(hide yes)
			(effects
				(font
					(size 1.27 1.27)
				)
				(justify mirror)
			)
		)
		(property "Value" ""
			(at 0 0 90)
			(layer "B.Fab")
			(effects
				(font
					(size 1.27 1.27)
				)
				(justify mirror)
			)
		)
		(duplicate_pad_numbers_are_jumpers no)
		(fp_line
			(start -0.7874 0.4064)
			(end 0.7874 0.4064)
			(stroke
				(width 0.1524)
				(type default)
			)
			(layer "B.SilkS")
		)
		(fp_line
			(start 0.7874 0.4064)
			(end 0.7874 -0.4064)
			(stroke
				(width 0.1524)
				(type default)
			)
			(layer "B.SilkS")
		)
		(fp_line
			(start -0.7874 -0.4064)
			(end -0.7874 0.4064)
			(stroke
				(width 0.1524)
				(type default)
			)
			(layer "B.SilkS")
		)
		(fp_line
			(start 0.7874 -0.4064)
			(end -0.7874 -0.4064)
			(stroke
				(width 0.1524)
				(type default)
			)
			(layer "B.SilkS")
		)
		(fp_line
			(start -0.67945 0.3048)
			(end -0.120396 0.3048)
			(stroke
				(width 0.1)
				(type default)
			)
			(layer "B.Fab")
		)
		(fp_line
			(start -0.120396 0.3048)
			(end -0.120396 0.2794)
			(stroke
				(width 0.1)
				(type default)
			)
			(layer "B.Fab")
		)
		(fp_line
			(start 0.12065 0.3048)
			(end 0.67945 0.3048)
			(stroke
				(width 0.1)
				(type default)
			)
			(layer "B.Fab")
		)
		(fp_line
			(start 0.67945 0.3048)
			(end 0.67945 -0.305054)
			(stroke
				(width 0.1)
				(type default)
			)
			(layer "B.Fab")
		)
		(fp_line
			(start -0.120396 0.2794)
			(end 0.12065 0.2794)
			(stroke
				(width 0.1)
				(type default)
			)
			(layer "B.Fab")
		)
		(fp_line
			(start 0.12065 0.2794)
			(end 0.12065 0.3048)
			(stroke
				(width 0.1)
				(type default)
			)
			(layer "B.Fab")
		)
		(fp_line
			(start -0.12065 -0.2794)
			(end -0.12065 -0.3048)
			(stroke
				(width 0.1)
				(type default)
			)
			(layer "B.Fab")
		)
		(fp_line
			(start 0.12065 -0.2794)
			(end -0.12065 -0.2794)
			(stroke
				(width 0.1)
				(type default)
			)
			(layer "B.Fab")
		)
		(fp_line
			(start -0.67945 -0.3048)
			(end -0.67945 0.3048)
			(stroke
				(width 0.1)
				(type default)
			)
			(layer "B.Fab")
		)
		(fp_line
			(start -0.12065 -0.3048)
			(end -0.67945 -0.3048)
			(stroke
				(width 0.1)
				(type default)
			)
			(layer "B.Fab")
		)
		(fp_line
			(start 0.12065 -0.305054)
			(end 0.12065 -0.2794)
			(stroke
				(width 0.1)
				(type default)
			)
			(layer "B.Fab")
		)
		(fp_line
			(start 0.67945 -0.305054)
			(end 0.12065 -0.305054)
			(stroke
				(width 0.1)
				(type default)
			)
			(layer "B.Fab")
		)
		(pad "1" smd circle
			(at 0.40005 0 90)
			(size 0 0)
			(layers "B.Cu" "B.Mask" "B.Paste")
			(net "PWRGD_PLT_AUX_CPU1_LVT3_R")
		)
		(pad "2" smd circle
			(at -0.40005 0 90)
			(size 0 0)
			(layers "B.Cu" "B.Mask" "B.Paste")
			(net "PWRGD_PLT_AUX_CPU1_LVT3")
		)
	)
)
